(kicad_pcb
	(version 20260206)
	(generator "pcbnew")
	(generator_version "10.0")
	(general
		(thickness 1.6)
		(legacy_teardrops no)
	)
	(paper "A4")
	(title_block
		(title "Wiwynn_Tioga_Pass_MB.brd")
		(comment 1 "Tioga Pass / footprint 2254 of 4770 (U5D1), pads 1323-1428 of 3647")
	)
	(layers
		(0 "F.Cu" signal "TOP")
		(4 "In1.Cu" signal "L2GND")
		(6 "In2.Cu" signal "L3")
		(8 "In3.Cu" signal "L4GND")
		(10 "In4.Cu" signal "L5")
		(12 "In5.Cu" signal "L6GND")
		(14 "In6.Cu" signal "L7VCC")
		(16 "In7.Cu" signal "L8VCC")
		(18 "In8.Cu" signal "L9GND")
		(20 "In9.Cu" signal "L10")
		(22 "In10.Cu" signal "L11GND")
		(24 "In11.Cu" signal "L12")
		(26 "In12.Cu" signal "L13GND")
		(2 "B.Cu" signal "BOTTOM")
		(9 "F.Adhes" user "F.Adhesive")
		(11 "B.Adhes" user "B.Adhesive")
		(13 "F.Paste" user "Package Geometry/Pastemask Top")
		(15 "B.Paste" user "Package Geometry/Pastemask Bottom")
		(5 "F.SilkS" user "Ref Des/Silkscreen Top")
		(7 "B.SilkS" user "Ref Des/Silkscreen Bottom")
		(1 "F.Mask" user "Board Geometry/Soldermask Top")
		(3 "B.Mask" user "Board Geometry/Soldermask Bottom")
		(17 "Dwgs.User" user "User.Drawings")
		(19 "Cmts.User" user "User.Comments")
		(21 "Eco1.User" user "User.Eco1")
		(23 "Eco2.User" user "User.Eco2")
		(25 "Edge.Cuts" user "Board Geometry/Outline")
		(27 "Margin" user)
		(31 "F.CrtYd" user "Package Geometry/Place Bound Top")
		(29 "B.CrtYd" user "Package Geometry/Place Bound Bottom")
		(35 "F.Fab" user "Ref Des/Assembly Top")
		(33 "B.Fab" user "Ref Des/Assembly Bottom")
	)
	(footprint ""
		(layer "F.Cu")
		(at 270.000222 -76.550012 180)
		(property "Reference" "U5D1"
			(at 19.124422 31.601918 0)
			(unlocked yes)
			(layer "F.SilkS")
			(effects
				(font
					(size 0.7874 0.5842)
					(thickness 0.1524)
				)
			)
		)
		(property "Value" ""
			(at 0 0 180)
			(layer "F.Fab")
			(effects
				(font
					(size 1.27 1.27)
				)
			)
		)
		(duplicate_pad_numbers_are_jumpers no)
		(pad "CA84" smd custom
			(at 35.533584 2.814828 270)
			(size 0.10795 0.10795)
			(layers "F.Cu" "F.Mask" "F.Paste")
			(net "PVCCIN_CPU0")
			(options
				(clearance outline)
				(anchor circle)
			)
			(primitives
				(gr_poly
					(pts
						(arc
							(start 0.2159 -0.0381)
							(mid 0 -0.254)
							(end -0.2159 -0.0381)
						)
						(arc
							(start -0.2159 0.0381)
							(mid 0 0.254)
							(end 0.2159 0.0381)
						)
					)
					(width 0)
					(fill yes)
				)
			)
		)
		(pad "CB3" smd circle
			(at -35.533584 5.109972)
			(size 0.4318 0.4318)
			(layers "F.Cu" "F.Mask" "F.Paste")
			(net "P3E_CPU0_PE2_SS_TXN<9>")
		)
		(pad "CB5" smd circle
			(at -33.816544 5.109972)
			(size 0.4318 0.4318)
			(layers "F.Cu" "F.Mask" "F.Paste")
			(net "TP_CPU0_RSVD_113")
		)
		(pad "CB7" smd circle
			(at -32.099504 5.109972)
			(size 0.4318 0.4318)
			(layers "F.Cu" "F.Mask" "F.Paste")
			(net "GND")
		)
		(pad "CB9" smd circle
			(at -30.382464 5.109972)
			(size 0.4318 0.4318)
			(layers "F.Cu" "F.Mask" "F.Paste")
			(net "GND")
		)
		(pad "CB11" smd circle
			(at -28.665424 5.109972)
			(size 0.4318 0.4318)
			(layers "F.Cu" "F.Mask" "F.Paste")
			(net "TP_CPU0_UPI2_RSVD_DN20")
		)
		(pad "CB13" smd circle
			(at -26.948384 5.109972)
			(size 0.4318 0.4318)
			(layers "F.Cu" "F.Mask" "F.Paste")
			(net "PVCCIO_CPU0")
		)
		(pad "CB15" smd circle
			(at -25.231598 5.109972)
			(size 0.4318 0.4318)
			(layers "F.Cu" "F.Mask" "F.Paste")
			(net "GND")
		)
		(pad "CB17" smd circle
			(at -23.514558 5.109972)
			(size 0.4318 0.4318)
			(layers "F.Cu" "F.Mask" "F.Paste")
			(net "PVCCIO_CPU0")
		)
		(pad "CB19" smd circle
			(at -21.797518 5.109972)
			(size 0.4318 0.4318)
			(layers "F.Cu" "F.Mask" "F.Paste")
			(net "PVCCMCP_CPU0")
		)
		(pad "CB21" smd circle
			(at -20.080478 5.109972)
			(size 0.4318 0.4318)
			(layers "F.Cu" "F.Mask" "F.Paste")
			(net "PVCCMCP_CPU0")
		)
		(pad "CB23" smd circle
			(at -18.363438 5.109972)
			(size 0.4318 0.4318)
			(layers "F.Cu" "F.Mask" "F.Paste")
			(net "JTAG_MCP_TCK")
		)
		(pad "CB25" smd circle
			(at -16.646398 5.109972)
			(size 0.4318 0.4318)
			(layers "F.Cu" "F.Mask" "F.Paste")
			(net "TP_CPU0_RSVD_114")
		)
		(pad "CB27" smd circle
			(at -14.929612 5.109972)
			(size 0.4318 0.4318)
			(layers "F.Cu" "F.Mask" "F.Paste")
			(net "GND")
		)
		(pad "CB61" smd circle
			(at 15.787878 3.309874)
			(size 0.4318 0.4318)
			(layers "F.Cu" "F.Mask" "F.Paste")
			(net "PVCCIN_CPU0")
		)
		(pad "CB63" smd circle
			(at 17.504918 3.309874)
			(size 0.4318 0.4318)
			(layers "F.Cu" "F.Mask" "F.Paste")
			(net "GND")
		)
		(pad "CB65" smd circle
			(at 19.221958 3.309874)
			(size 0.4318 0.4318)
			(layers "F.Cu" "F.Mask" "F.Paste")
			(net "PVSA_CPU0")
		)
		(pad "CB67" smd circle
			(at 20.938998 3.309874)
			(size 0.4318 0.4318)
			(layers "F.Cu" "F.Mask" "F.Paste")
			(net "PVSA_CPU0")
		)
		(pad "CB69" smd circle
			(at 22.656038 3.309874)
			(size 0.4318 0.4318)
			(layers "F.Cu" "F.Mask" "F.Paste")
			(net "PVSA_CPU0")
		)
		(pad "CB71" smd circle
			(at 24.373078 3.309874)
			(size 0.4318 0.4318)
			(layers "F.Cu" "F.Mask" "F.Paste")
			(net "GND")
		)
		(pad "CB73" smd circle
			(at 26.090118 3.309874)
			(size 0.4318 0.4318)
			(layers "F.Cu" "F.Mask" "F.Paste")
			(net "PVCCIN_CPU0")
		)
		(pad "CB75" smd circle
			(at 27.806904 3.309874)
			(size 0.4318 0.4318)
			(layers "F.Cu" "F.Mask" "F.Paste")
			(net "PVCCIN_CPU0")
		)
		(pad "CB77" smd circle
			(at 29.523944 3.309874)
			(size 0.4318 0.4318)
			(layers "F.Cu" "F.Mask" "F.Paste")
			(net "PVCCIN_CPU0")
		)
		(pad "CB79" smd circle
			(at 31.240984 3.309874)
			(size 0.4318 0.4318)
			(layers "F.Cu" "F.Mask" "F.Paste")
			(net "PVCCIN_CPU0")
		)
		(pad "CB81" smd circle
			(at 32.958024 3.309874)
			(size 0.4318 0.4318)
			(layers "F.Cu" "F.Mask" "F.Paste")
			(net "PVCCIN_CPU0")
		)
		(pad "CB83" smd circle
			(at 34.675064 3.309874)
			(size 0.4318 0.4318)
			(layers "F.Cu" "F.Mask" "F.Paste")
			(net "PVCCIN_CPU0")
		)
		(pad "CC2" smd custom
			(at -36.392104 5.605272 90)
			(size 0.10795 0.10795)
			(layers "F.Cu" "F.Mask" "F.Paste")
			(net "P3E_CPU0_PE2_SS_TXN<8>")
			(options
				(clearance outline)
				(anchor circle)
			)
			(primitives
				(gr_poly
					(pts
						(arc
							(start 0.2159 -0.0381)
							(mid 0 -0.254)
							(end -0.2159 -0.0381)
						)
						(arc
							(start -0.2159 0.0381)
							(mid 0 0.254)
							(end 0.2159 0.0381)
						)
					)
					(width 0)
					(fill yes)
				)
			)
		)
		(pad "CC4" smd circle
			(at -34.675064 5.605272)
			(size 0.4318 0.4318)
			(layers "F.Cu" "F.Mask" "F.Paste")
			(net "GND")
		)
		(pad "CC6" smd circle
			(at -32.958024 5.605272)
			(size 0.4318 0.4318)
			(layers "F.Cu" "F.Mask" "F.Paste")
			(net "TP_CPU0_RSVD_111")
		)
		(pad "CC8" smd circle
			(at -31.240984 5.605272)
			(size 0.4318 0.4318)
			(layers "F.Cu" "F.Mask" "F.Paste")
			(net "P3E_CPU0_PE2_SS_RXP<7>")
		)
		(pad "CC10" smd circle
			(at -29.523944 5.605272)
			(size 0.4318 0.4318)
			(layers "F.Cu" "F.Mask" "F.Paste")
			(net "TP_CPU0_UPI2_RSVD_DM21")
		)
		(pad "CC12" smd circle
			(at -27.806904 5.605272)
			(size 0.4318 0.4318)
			(layers "F.Cu" "F.Mask" "F.Paste")
			(net "TP_CPU0_UPI2_RSVD_DT21")
		)
		(pad "CC14" smd circle
			(at -26.090118 5.605272)
			(size 0.4318 0.4318)
			(layers "F.Cu" "F.Mask" "F.Paste")
			(net "GND")
		)
		(pad "CC16" smd circle
			(at -24.373078 5.605272)
			(size 0.4318 0.4318)
			(layers "F.Cu" "F.Mask" "F.Paste")
			(net "GND")
		)
		(pad "CC18" smd circle
			(at -22.656038 5.605272)
			(size 0.4318 0.4318)
			(layers "F.Cu" "F.Mask" "F.Paste")
			(net "GND")
		)
		(pad "CC20" smd circle
			(at -20.938998 5.605272)
			(size 0.4318 0.4318)
			(layers "F.Cu" "F.Mask" "F.Paste")
			(net "PVCCMCP_CPU0")
		)
		(pad "CC22" smd circle
			(at -19.221958 5.605272)
			(size 0.4318 0.4318)
			(layers "F.Cu" "F.Mask" "F.Paste")
			(net "JTAG_MCP_CPU0_TDO")
		)
		(pad "CC24" smd circle
			(at -17.504918 5.605272)
			(size 0.4318 0.4318)
			(layers "F.Cu" "F.Mask" "F.Paste")
			(net "GND")
		)
		(pad "CC26" smd circle
			(at -15.787878 5.605272)
			(size 0.4318 0.4318)
			(layers "F.Cu" "F.Mask" "F.Paste")
			(net "PVCCIO_CPU0")
		)
		(pad "CC60" smd circle
			(at 14.929612 3.805428)
			(size 0.508 0.508)
			(layers "F.Cu" "F.Mask" "F.Paste")
			(net "PVCCIN_CPU0")
		)
		(pad "CC62" smd circle
			(at 16.646398 3.805428)
			(size 0.4318 0.4318)
			(layers "F.Cu" "F.Mask" "F.Paste")
			(net "PVCCIN_CPU0")
		)
		(pad "CC64" smd circle
			(at 18.363438 3.805428)
			(size 0.4318 0.4318)
			(layers "F.Cu" "F.Mask" "F.Paste")
			(net "GND")
		)
		(pad "CC66" smd circle
			(at 20.080478 3.805428)
			(size 0.4318 0.4318)
			(layers "F.Cu" "F.Mask" "F.Paste")
			(net "PVSA_CPU0")
		)
		(pad "CC68" smd circle
			(at 21.797518 3.805428)
			(size 0.4318 0.4318)
			(layers "F.Cu" "F.Mask" "F.Paste")
			(net "PVSA_CPU0")
		)
		(pad "CC70" smd circle
			(at 23.514558 3.805428)
			(size 0.4318 0.4318)
			(layers "F.Cu" "F.Mask" "F.Paste")
			(net "PVSA_CPU0")
		)
		(pad "CC72" smd circle
			(at 25.231598 3.805428)
			(size 0.4318 0.4318)
			(layers "F.Cu" "F.Mask" "F.Paste")
			(net "GND")
		)
		(pad "CC74" smd circle
			(at 26.948384 3.805428)
			(size 0.4318 0.4318)
			(layers "F.Cu" "F.Mask" "F.Paste")
			(net "GND")
		)
		(pad "CC76" smd circle
			(at 28.665424 3.805428)
			(size 0.4318 0.4318)
			(layers "F.Cu" "F.Mask" "F.Paste")
			(net "GND")
		)
		(pad "CC78" smd circle
			(at 30.382464 3.805428)
			(size 0.4318 0.4318)
			(layers "F.Cu" "F.Mask" "F.Paste")
			(net "GND")
		)
		(pad "CC80" smd circle
			(at 32.099504 3.805428)
			(size 0.4318 0.4318)
			(layers "F.Cu" "F.Mask" "F.Paste")
			(net "GND")
		)
		(pad "CC82" smd circle
			(at 33.816544 3.805428)
			(size 0.4318 0.4318)
			(layers "F.Cu" "F.Mask" "F.Paste")
			(net "GND")
		)
		(pad "CC84" smd custom
			(at 35.533584 3.805428 270)
			(size 0.10795 0.10795)
			(layers "F.Cu" "F.Mask" "F.Paste")
			(net "PVCCIN_CPU0")
			(options
				(clearance outline)
				(anchor circle)
			)
			(primitives
				(gr_poly
					(pts
						(arc
							(start 0.2159 -0.0381)
							(mid 0 -0.254)
							(end -0.2159 -0.0381)
						)
						(arc
							(start -0.2159 0.0381)
							(mid 0 0.254)
							(end 0.2159 0.0381)
						)
					)
					(width 0)
					(fill yes)
				)
			)
		)
		(pad "CD3" smd circle
			(at -35.533584 6.100572)
			(size 0.4318 0.4318)
			(layers "F.Cu" "F.Mask" "F.Paste")
			(net "P3E_CPU0_PE2_SS_TXP<8>")
		)
		(pad "CD5" smd circle
			(at -33.816544 6.100572)
			(size 0.4318 0.4318)
			(layers "F.Cu" "F.Mask" "F.Paste")
			(net "GND")
		)
		(pad "CD7" smd circle
			(at -32.099504 6.100572)
			(size 0.4318 0.4318)
			(layers "F.Cu" "F.Mask" "F.Paste")
			(net "P3E_CPU0_PE2_SS_RXP<6>")
		)
		(pad "CD9" smd circle
			(at -30.382464 6.100572)
			(size 0.4318 0.4318)
			(layers "F.Cu" "F.Mask" "F.Paste")
			(net "PVCCIO_CPU0")
		)
		(pad "CD11" smd circle
			(at -28.665424 6.100572)
			(size 0.4318 0.4318)
			(layers "F.Cu" "F.Mask" "F.Paste")
			(net "TP_CPU0_UPI2_RSVD_DK19")
		)
		(pad "CD13" smd circle
			(at -26.948384 6.100572)
			(size 0.4318 0.4318)
			(layers "F.Cu" "F.Mask" "F.Paste")
			(net "GND")
		)
		(pad "CD15" smd circle
			(at -25.231598 6.100572)
			(size 0.4318 0.4318)
			(layers "F.Cu" "F.Mask" "F.Paste")
			(net "GND")
		)
		(pad "CD17" smd circle
			(at -23.514558 6.100572)
			(size 0.4318 0.4318)
			(layers "F.Cu" "F.Mask" "F.Paste")
			(net "GND")
		)
		(pad "CD19" smd circle
			(at -21.797518 6.100572)
			(size 0.4318 0.4318)
			(layers "F.Cu" "F.Mask" "F.Paste")
			(net "PVCCMCP_CPU0")
		)
		(pad "CD21" smd circle
			(at -20.080478 6.100572)
			(size 0.4318 0.4318)
			(layers "F.Cu" "F.Mask" "F.Paste")
			(net "PVCCMCP_CPU0")
		)
		(pad "CD23" smd circle
			(at -18.363438 6.100572)
			(size 0.4318 0.4318)
			(layers "F.Cu" "F.Mask" "F.Paste")
			(net "JTAG_MCP_TRST_N")
		)
		(pad "CD25" smd circle
			(at -16.646398 6.100572)
			(size 0.4318 0.4318)
			(layers "F.Cu" "F.Mask" "F.Paste")
			(net "TP_CPU0_RSVD_108")
		)
		(pad "CD27" smd circle
			(at -14.929612 6.100572)
			(size 0.4318 0.4318)
			(layers "F.Cu" "F.Mask" "F.Paste")
			(net "PVCCIO_CPU0")
		)
		(pad "CD61" smd circle
			(at 15.787878 4.300474)
			(size 0.4318 0.4318)
			(layers "F.Cu" "F.Mask" "F.Paste")
			(net "PVCCIN_CPU0")
		)
		(pad "CD63" smd circle
			(at 17.504918 4.300474)
			(size 0.4318 0.4318)
			(layers "F.Cu" "F.Mask" "F.Paste")
			(net "GND")
		)
		(pad "CD65" smd circle
			(at 19.221958 4.300474)
			(size 0.4318 0.4318)
			(layers "F.Cu" "F.Mask" "F.Paste")
			(net "PVSA_CPU0")
		)
		(pad "CD67" smd circle
			(at 20.938998 4.300474)
			(size 0.4318 0.4318)
			(layers "F.Cu" "F.Mask" "F.Paste")
			(net "PVSA_CPU0")
		)
		(pad "CD69" smd circle
			(at 22.656038 4.300474)
			(size 0.4318 0.4318)
			(layers "F.Cu" "F.Mask" "F.Paste")
			(net "PVSA_CPU0")
		)
		(pad "CD71" smd circle
			(at 24.373078 4.300474)
			(size 0.4318 0.4318)
			(layers "F.Cu" "F.Mask" "F.Paste")
			(net "PVSA_CPU0")
		)
		(pad "CD73" smd circle
			(at 26.090118 4.300474)
			(size 0.4318 0.4318)
			(layers "F.Cu" "F.Mask" "F.Paste")
			(net "GND")
		)
		(pad "CD75" smd circle
			(at 27.806904 4.300474)
			(size 0.4318 0.4318)
			(layers "F.Cu" "F.Mask" "F.Paste")
			(net "GND")
		)
		(pad "CD77" smd circle
			(at 29.523944 4.300474)
			(size 0.4318 0.4318)
			(layers "F.Cu" "F.Mask" "F.Paste")
			(net "GND")
		)
		(pad "CD79" smd circle
			(at 31.240984 4.300474)
			(size 0.4318 0.4318)
			(layers "F.Cu" "F.Mask" "F.Paste")
			(net "GND")
		)
		(pad "CD81" smd circle
			(at 32.958024 4.300474)
			(size 0.4318 0.4318)
			(layers "F.Cu" "F.Mask" "F.Paste")
			(net "GND")
		)
		(pad "CD83" smd circle
			(at 34.675064 4.300474)
			(size 0.4318 0.4318)
			(layers "F.Cu" "F.Mask" "F.Paste")
			(net "PVCCIN_CPU0")
		)
		(pad "CD85" smd custom
			(at 36.392104 4.300474 270)
			(size 0.10795 0.10795)
			(layers "F.Cu" "F.Mask" "F.Paste")
			(net "PVCCIN_CPU0")
			(options
				(clearance outline)
				(anchor circle)
			)
			(primitives
				(gr_poly
					(pts
						(arc
							(start 0.2159 -0.0381)
							(mid 0 -0.254)
							(end -0.2159 -0.0381)
						)
						(arc
							(start -0.2159 0.0381)
							(mid 0 0.254)
							(end 0.2159 0.0381)
						)
					)
					(width 0)
					(fill yes)
				)
			)
		)
		(pad "CE2" smd custom
			(at -36.392104 6.596126 90)
			(size 0.10795 0.10795)
			(layers "F.Cu" "F.Mask" "F.Paste")
			(net "P3E_CPU0_PE2_SS_TXP<6>")
			(options
				(clearance outline)
				(anchor circle)
			)
			(primitives
				(gr_poly
					(pts
						(arc
							(start 0.2159 -0.0381)
							(mid 0 -0.254)
							(end -0.2159 -0.0381)
						)
						(arc
							(start -0.2159 0.0381)
							(mid 0 0.254)
							(end 0.2159 0.0381)
						)
					)
					(width 0)
					(fill yes)
				)
			)
		)
		(pad "CE4" smd circle
			(at -34.675064 6.596126)
			(size 0.4318 0.4318)
			(layers "F.Cu" "F.Mask" "F.Paste")
			(net "P3E_CPU0_PE2_SS_TXP<7>")
		)
		(pad "CE6" smd circle
			(at -32.958024 6.596126)
			(size 0.4318 0.4318)
			(layers "F.Cu" "F.Mask" "F.Paste")
			(net "P3E_CPU0_PE2_SS_RXN<6>")
		)
		(pad "CE8" smd circle
			(at -31.240984 6.596126)
			(size 0.4318 0.4318)
			(layers "F.Cu" "F.Mask" "F.Paste")
			(net "P3E_CPU0_PE2_SS_RXN<7>")
		)
		(pad "CE10" smd circle
			(at -29.523944 6.596126)
			(size 0.4318 0.4318)
			(layers "F.Cu" "F.Mask" "F.Paste")
			(net "GND")
		)
		(pad "CE12" smd circle
			(at -27.806904 6.596126)
			(size 0.4318 0.4318)
			(layers "F.Cu" "F.Mask" "F.Paste")
			(net "TP_CPU0_UPI2_RSVD_DL20")
		)
		(pad "CE14" smd circle
			(at -26.090118 6.596126)
			(size 0.4318 0.4318)
			(layers "F.Cu" "F.Mask" "F.Paste")
			(net "GND")
		)
		(pad "CE16" smd circle
			(at -24.373078 6.596126)
			(size 0.4318 0.4318)
			(layers "F.Cu" "F.Mask" "F.Paste")
			(net "GND")
		)
		(pad "CE18" smd circle
			(at -22.656038 6.596126)
			(size 0.4318 0.4318)
			(layers "F.Cu" "F.Mask" "F.Paste")
			(net "PVCCIO_CPU0")
		)
		(pad "CE20" smd circle
			(at -20.938998 6.596126)
			(size 0.4318 0.4318)
			(layers "F.Cu" "F.Mask" "F.Paste")
			(net "GND")
		)
		(pad "CE22" smd circle
			(at -19.221958 6.596126)
			(size 0.4318 0.4318)
			(layers "F.Cu" "F.Mask" "F.Paste")
			(net "PVCCMCP_CPU0")
		)
		(pad "CE24" smd circle
			(at -17.504918 6.596126)
			(size 0.4318 0.4318)
			(layers "F.Cu" "F.Mask" "F.Paste")
			(net "JTAG_MCP_TMS")
		)
		(pad "CE26" smd circle
			(at -15.787878 6.596126)
			(size 0.4318 0.4318)
			(layers "F.Cu" "F.Mask" "F.Paste")
			(net "GND")
		)
		(pad "CE60" smd circle
			(at 14.929612 4.796028)
			(size 0.508 0.508)
			(layers "F.Cu" "F.Mask" "F.Paste")
			(net "PVCCIN_CPU0")
		)
		(pad "CE62" smd circle
			(at 16.646398 4.796028)
			(size 0.4318 0.4318)
			(layers "F.Cu" "F.Mask" "F.Paste")
			(net "GND")
		)
		(pad "CE64" smd circle
			(at 18.363438 4.796028)
			(size 0.4318 0.4318)
			(layers "F.Cu" "F.Mask" "F.Paste")
			(net "PVSA_CPU0")
		)
		(pad "CE66" smd circle
			(at 20.080478 4.796028)
			(size 0.4318 0.4318)
			(layers "F.Cu" "F.Mask" "F.Paste")
			(net "PVSA_CPU0")
		)
		(pad "CE68" smd circle
			(at 21.797518 4.796028)
			(size 0.4318 0.4318)
			(layers "F.Cu" "F.Mask" "F.Paste")
			(net "PVSA_CPU0")
		)
		(pad "CE70" smd circle
			(at 23.514558 4.796028)
			(size 0.4318 0.4318)
			(layers "F.Cu" "F.Mask" "F.Paste")
			(net "GND")
		)
		(pad "CE72" smd circle
			(at 25.231598 4.796028)
			(size 0.4318 0.4318)
			(layers "F.Cu" "F.Mask" "F.Paste")
			(net "PVSA_CPU0")
		)
		(pad "CE74" smd circle
			(at 26.948384 4.796028)
			(size 0.4318 0.4318)
			(layers "F.Cu" "F.Mask" "F.Paste")
			(net "PVSA_CPU0")
		)
		(pad "CE76" smd circle
			(at 28.665424 4.796028)
			(size 0.4318 0.4318)
			(layers "F.Cu" "F.Mask" "F.Paste")
			(net "VSENSE_PVSA_CPU0_SKT_VSEN")
		)
		(pad "CE78" smd circle
			(at 30.382464 4.796028)
			(size 0.4318 0.4318)
			(layers "F.Cu" "F.Mask" "F.Paste")
			(net "TP_CPU0_RSVD_106")
		)
		(pad "CE80" smd circle
			(at 32.099504 4.796028)
			(size 0.4318 0.4318)
			(layers "F.Cu" "F.Mask" "F.Paste")
			(net "TP_CPU0_RSVD_105")
		)
		(pad "CE82" smd circle
			(at 33.816544 4.796028)
			(size 0.4318 0.4318)
			(layers "F.Cu" "F.Mask" "F.Paste")
			(net "GND")
		)
		(pad "CE84" smd circle
			(at 35.533584 4.796028)
			(size 0.4318 0.4318)
			(layers "F.Cu" "F.Mask" "F.Paste")
			(net "PVCCIN_CPU0")
		)
		(pad "CF3" smd circle
			(at -35.533584 7.091172)
			(size 0.4318 0.4318)
			(layers "F.Cu" "F.Mask" "F.Paste")
			(net "P3E_CPU0_PE2_SS_TXN<7>")
		)
		(pad "CF5" smd circle
			(at -33.816544 7.091172)
			(size 0.4318 0.4318)
			(layers "F.Cu" "F.Mask" "F.Paste")
			(net "PVCCIO_CPU0")
		)
	)
)
